(kicad_pcb
	(version 20260206)
	(generator "pcbnew")
	(generator_version "10.0")
	(general
		(thickness 1.6)
		(legacy_teardrops no)
	)
	(paper "A4")
	(title_block
		(title "pdpb — Lightning_PDPB_BRD.brd")
		(comment 1 "Lightning (Wiwynn / Facebook NVMe JBOF) / footprints 37-43 of 1140")
	)
	(layers
		(0 "F.Cu" signal "TOP")
		(4 "In1.Cu" signal "L2GND")
		(6 "In2.Cu" signal "L3")
		(8 "In3.Cu" signal "L4VCC")
		(10 "In4.Cu" signal "L5VCC")
		(12 "In5.Cu" signal "L6")
		(14 "In6.Cu" signal "L7GND")
		(2 "B.Cu" signal "BOTTOM")
		(9 "F.Adhes" user "F.Adhesive")
		(11 "B.Adhes" user "B.Adhesive")
		(13 "F.Paste" user "Package Geometry/Pastemask Top")
		(15 "B.Paste" user "Package Geometry/Pastemask Bottom")
		(5 "F.SilkS" user "Ref Des/Silkscreen Top")
		(7 "B.SilkS" user "Ref Des/Silkscreen Bottom")
		(1 "F.Mask" user "Board Geometry/Soldermask Top")
		(3 "B.Mask" user "Board Geometry/Soldermask Bottom")
		(17 "Dwgs.User" user "User.Drawings")
		(19 "Cmts.User" user "User.Comments")
		(21 "Eco1.User" user "User.Eco1")
		(23 "Eco2.User" user "User.Eco2")
		(25 "Edge.Cuts" user "Board Geometry/Outline")
		(27 "Margin" user)
		(31 "F.CrtYd" user "Package Geometry/Place Bound Top")
		(29 "B.CrtYd" user "Package Geometry/Place Bound Bottom")
		(35 "F.Fab" user "Ref Des/Assembly Top")
		(33 "B.Fab" user "Ref Des/Assembly Bottom")
	)
	(footprint ""
		(layer "F.Cu")
		(at 86.487 -423.164)
		(property "Reference" "R9069"
			(at 0 0 0)
			(layer "F.SilkS")
			(hide yes)
			(effects
				(font
					(size 1.27 1.27)
				)
			)
		)
		(property "Value" "27R2F-GP"
			(at 0.064008 -3.993896 0)
			(unlocked yes)
			(layer "F.Fab")
			(hide yes)
			(effects
				(font
					(size 1.016 1.016)
					(thickness 0.1524)
				)
			)
		)
		(property "Device Type" "R402H16"
			(at 0.064008 -5.517896 0)
			(unlocked yes)
			(layer "F.Fab")
			(hide yes)
			(effects
				(font
					(size 1.016 1.016)
					(thickness 0.1524)
				)
			)
		)
		(duplicate_pad_numbers_are_jumpers no)
		(fp_line
			(start -0.508 -0.9398)
			(end -0.508 0.9398)
			(stroke
				(width 0.1524)
				(type default)
			)
			(layer "F.SilkS")
		)
		(fp_line
			(start 0.508 -0.9398)
			(end -0.508 -0.9398)
			(stroke
				(width 0.1524)
				(type default)
			)
			(layer "F.SilkS")
		)
		(fp_rect
			(start -0.508 0.9398)
			(end 0.508 -0.9398)
			(stroke
				(width 0)
				(type default)
			)
			(fill no)
			(layer "F.CrtYd")
		)
		(fp_rect
			(start -0.508 0.9398)
			(end 0.508 -0.9398)
			(stroke
				(width 0)
				(type default)
			)
			(fill no)
			(layer "F.Fab")
		)
		(pad "1" smd custom
			(at 0 -0.4445)
			(size 0.1397 0.1397)
			(layers "F.Cu" "F.Mask" "F.Paste")
			(net "PE_CLK_100M_DR10_2_R_P")
			(options
				(clearance outline)
				(anchor circle)
			)
			(primitives
				(gr_poly
					(pts
						(arc
							(start -0.1778 -0.2794)
							(mid -0.249642 -0.249642)
							(end -0.2794 -0.1778)
						)
						(arc
							(start -0.2794 0.1778)
							(mid -0.249642 0.249642)
							(end -0.1778 0.2794)
						)
						(arc
							(start 0.1778 0.2794)
							(mid 0.249642 0.249642)
							(end 0.2794 0.1778)
						)
						(arc
							(start 0.2794 -0.1778)
							(mid 0.249642 -0.249642)
							(end 0.1778 -0.2794)
						)
					)
					(width 0)
					(fill yes)
				)
			)
		)
		(pad "2" smd custom
			(at 0 0.4445)
			(size 0.1397 0.1397)
			(layers "F.Cu" "F.Mask" "F.Paste")
			(net "PE_CLK100M_DR10_2_P")
			(options
				(clearance outline)
				(anchor circle)
			)
			(primitives
				(gr_poly
					(pts
						(arc
							(start -0.1778 -0.2794)
							(mid -0.249642 -0.249642)
							(end -0.2794 -0.1778)
						)
						(arc
							(start -0.2794 0.1778)
							(mid -0.249642 0.249642)
							(end -0.1778 0.2794)
						)
						(arc
							(start 0.1778 0.2794)
							(mid 0.249642 0.249642)
							(end 0.2794 0.1778)
						)
						(arc
							(start 0.2794 -0.1778)
							(mid 0.249642 -0.249642)
							(end 0.1778 -0.2794)
						)
					)
					(width 0)
					(fill yes)
				)
			)
		)
	)
	(footprint ""
		(layer "F.Cu")
		(at 209.677 -454.66 180)
		(property "Reference" "R316"
			(at 0 0 180)
			(layer "F.SilkS")
			(hide yes)
			(effects
				(font
					(size 1.27 1.27)
				)
			)
		)
		(property "Value" "4K7R2F-GP"
			(at 0.064008 -3.993896 180)
			(unlocked yes)
			(layer "F.Fab")
			(hide yes)
			(effects
				(font
					(size 1.016 1.016)
					(thickness 0.1524)
				)
			)
		)
		(property "Device Type" "R402H16"
			(at 0.064008 -5.517896 180)
			(unlocked yes)
			(layer "F.Fab")
			(hide yes)
			(effects
				(font
					(size 1.016 1.016)
					(thickness 0.1524)
				)
			)
		)
		(duplicate_pad_numbers_are_jumpers no)
		(fp_line
			(start 0.508 -0.9398)
			(end -0.508 -0.9398)
			(stroke
				(width 0.1524)
				(type default)
			)
			(layer "F.SilkS")
		)
		(fp_line
			(start -0.508 -0.9398)
			(end -0.508 0.9398)
			(stroke
				(width 0.1524)
				(type default)
			)
			(layer "F.SilkS")
		)
		(fp_rect
			(start -0.508 0.9398)
			(end 0.508 -0.9398)
			(stroke
				(width 0)
				(type default)
			)
			(fill no)
			(layer "F.CrtYd")
		)
		(fp_rect
			(start -0.508 0.9398)
			(end 0.508 -0.9398)
			(stroke
				(width 0)
				(type default)
			)
			(fill no)
			(layer "F.Fab")
		)
		(pad "1" smd custom
			(at 0 -0.4445 180)
			(size 0.1397 0.1397)
			(layers "F.Cu" "F.Mask" "F.Paste")
			(net "P3V3")
			(options
				(clearance outline)
				(anchor circle)
			)
			(primitives
				(gr_poly
					(pts
						(arc
							(start -0.1778 -0.2794)
							(mid -0.249642 -0.249642)
							(end -0.2794 -0.1778)
						)
						(arc
							(start -0.2794 0.1778)
							(mid -0.249642 0.249642)
							(end -0.1778 0.2794)
						)
						(arc
							(start 0.1778 0.2794)
							(mid 0.249642 0.249642)
							(end 0.2794 0.1778)
						)
						(arc
							(start 0.2794 -0.1778)
							(mid 0.249642 -0.249642)
							(end 0.1778 -0.2794)
						)
					)
					(width 0)
					(fill yes)
				)
			)
		)
		(pad "2" smd custom
			(at 0 0.4445 180)
			(size 0.1397 0.1397)
			(layers "F.Cu" "F.Mask" "F.Paste")
			(net "I2C_B_TMP2_A1")
			(options
				(clearance outline)
				(anchor circle)
			)
			(primitives
				(gr_poly
					(pts
						(arc
							(start -0.1778 -0.2794)
							(mid -0.249642 -0.249642)
							(end -0.2794 -0.1778)
						)
						(arc
							(start -0.2794 0.1778)
							(mid -0.249642 0.249642)
							(end -0.1778 0.2794)
						)
						(arc
							(start 0.1778 0.2794)
							(mid 0.249642 0.249642)
							(end 0.2794 0.1778)
						)
						(arc
							(start 0.2794 -0.1778)
							(mid 0.249642 -0.249642)
							(end 0.1778 -0.2794)
						)
					)
					(width 0)
					(fill yes)
				)
			)
		)
	)
	(footprint ""
		(layer "F.Cu")
		(at 24.8158 -191.643 -90)
		(property "Reference" "R146"
			(at 0 0 270)
			(layer "F.SilkS")
			(hide yes)
			(effects
				(font
					(size 1.27 1.27)
				)
			)
		)
		(property "Value" "4K7R2J-2-GP"
			(at 0.064008 -3.993896 270)
			(unlocked yes)
			(layer "F.Fab")
			(hide yes)
			(effects
				(font
					(size 1.016 1.016)
					(thickness 0.1524)
				)
			)
		)
		(property "Device Type" "R402H16"
			(at 0.064008 -5.517896 270)
			(unlocked yes)
			(layer "F.Fab")
			(hide yes)
			(effects
				(font
					(size 1.016 1.016)
					(thickness 0.1524)
				)
			)
		)
		(duplicate_pad_numbers_are_jumpers no)
		(fp_line
			(start -0.508 -0.9398)
			(end -0.508 0.9398)
			(stroke
				(width 0.1524)
				(type default)
			)
			(layer "F.SilkS")
		)
		(fp_line
			(start 0.508 -0.9398)
			(end -0.508 -0.9398)
			(stroke
				(width 0.1524)
				(type default)
			)
			(layer "F.SilkS")
		)
		(fp_rect
			(start -0.508 0.9398)
			(end 0.508 -0.9398)
			(stroke
				(width 0)
				(type default)
			)
			(fill no)
			(layer "F.CrtYd")
		)
		(fp_rect
			(start -0.508 0.9398)
			(end 0.508 -0.9398)
			(stroke
				(width 0)
				(type default)
			)
			(fill no)
			(layer "F.Fab")
		)
		(pad "1" smd custom
			(at 0 -0.4445 270)
			(size 0.1397 0.1397)
			(layers "F.Cu" "F.Mask" "F.Paste")
			(net "P12V")
			(options
				(clearance outline)
				(anchor circle)
			)
			(primitives
				(gr_poly
					(pts
						(arc
							(start -0.1778 -0.2794)
							(mid -0.249642 -0.249642)
							(end -0.2794 -0.1778)
						)
						(arc
							(start -0.2794 0.1778)
							(mid -0.249642 0.249642)
							(end -0.1778 0.2794)
						)
						(arc
							(start 0.1778 0.2794)
							(mid 0.249642 0.249642)
							(end 0.2794 0.1778)
						)
						(arc
							(start 0.2794 -0.1778)
							(mid 0.249642 -0.249642)
							(end 0.1778 -0.2794)
						)
					)
					(width 0)
					(fill yes)
				)
			)
		)
		(pad "2" smd custom
			(at 0 0.4445 270)
			(size 0.1397 0.1397)
			(layers "F.Cu" "F.Mask" "F.Paste")
			(net "SW_SSD8_R")
			(options
				(clearance outline)
				(anchor circle)
			)
			(primitives
				(gr_poly
					(pts
						(arc
							(start -0.1778 -0.2794)
							(mid -0.249642 -0.249642)
							(end -0.2794 -0.1778)
						)
						(arc
							(start -0.2794 0.1778)
							(mid -0.249642 0.249642)
							(end -0.1778 0.2794)
						)
						(arc
							(start 0.1778 0.2794)
							(mid 0.249642 0.249642)
							(end 0.2794 0.1778)
						)
						(arc
							(start 0.2794 -0.1778)
							(mid 0.249642 -0.249642)
							(end 0.1778 -0.2794)
						)
					)
					(width 0)
					(fill yes)
				)
			)
		)
	)
	(footprint ""
		(layer "F.Cu")
		(at 84.455 -427.99 90)
		(property "Reference" "R420"
			(at 0 0 90)
			(layer "F.SilkS")
			(hide yes)
			(effects
				(font
					(size 1.27 1.27)
				)
			)
		)
		(property "Value" "0R2J-2-GP"
			(at 0.064008 -3.993896 90)
			(unlocked yes)
			(layer "F.Fab")
			(hide yes)
			(effects
				(font
					(size 1.016 1.016)
					(thickness 0.1524)
				)
			)
		)
		(property "Device Type" "R402H16"
			(at 0.064008 -5.517896 90)
			(unlocked yes)
			(layer "F.Fab")
			(hide yes)
			(effects
				(font
					(size 1.016 1.016)
					(thickness 0.1524)
				)
			)
		)
		(duplicate_pad_numbers_are_jumpers no)
		(fp_line
			(start 0.508 -0.9398)
			(end -0.508 -0.9398)
			(stroke
				(width 0.1524)
				(type default)
			)
			(layer "F.SilkS")
		)
		(fp_line
			(start -0.508 -0.9398)
			(end -0.508 0.9398)
			(stroke
				(width 0.1524)
				(type default)
			)
			(layer "F.SilkS")
		)
		(fp_rect
			(start -0.508 0.9398)
			(end 0.508 -0.9398)
			(stroke
				(width 0)
				(type default)
			)
			(fill no)
			(layer "F.CrtYd")
		)
		(fp_rect
			(start -0.508 0.9398)
			(end 0.508 -0.9398)
			(stroke
				(width 0)
				(type default)
			)
			(fill no)
			(layer "F.Fab")
		)
		(pad "1" smd custom
			(at 0 -0.4445 90)
			(size 0.1397 0.1397)
			(layers "F.Cu" "F.Mask" "F.Paste")
			(net "BMC_I2C_SDA_BUF_9")
			(options
				(clearance outline)
				(anchor circle)
			)
			(primitives
				(gr_poly
					(pts
						(arc
							(start -0.1778 -0.2794)
							(mid -0.249642 -0.249642)
							(end -0.2794 -0.1778)
						)
						(arc
							(start -0.2794 0.1778)
							(mid -0.249642 0.249642)
							(end -0.1778 0.2794)
						)
						(arc
							(start 0.1778 0.2794)
							(mid 0.249642 0.249642)
							(end 0.2794 0.1778)
						)
						(arc
							(start 0.2794 -0.1778)
							(mid 0.249642 -0.249642)
							(end 0.1778 -0.2794)
						)
					)
					(width 0)
					(fill yes)
				)
			)
		)
		(pad "2" smd custom
			(at 0 0.4445 90)
			(size 0.1397 0.1397)
			(layers "F.Cu" "F.Mask" "F.Paste")
			(net "I2C_SDA_BUF_9_EU1_R")
			(options
				(clearance outline)
				(anchor circle)
			)
			(primitives
				(gr_poly
					(pts
						(arc
							(start -0.1778 -0.2794)
							(mid -0.249642 -0.249642)
							(end -0.2794 -0.1778)
						)
						(arc
							(start -0.2794 0.1778)
							(mid -0.249642 0.249642)
							(end -0.1778 0.2794)
						)
						(arc
							(start 0.1778 0.2794)
							(mid 0.249642 0.249642)
							(end 0.2794 0.1778)
						)
						(arc
							(start 0.2794 -0.1778)
							(mid 0.249642 -0.249642)
							(end 0.1778 -0.2794)
						)
					)
					(width 0)
					(fill yes)
				)
			)
		)
	)
	(footprint ""
		(layer "F.Cu")
		(at 99.949 -97.028 180)
		(property "Reference" "C8875"
			(at 0 0 180)
			(layer "F.SilkS")
			(hide yes)
			(effects
				(font
					(size 1.27 1.27)
				)
			)
		)
		(property "Value" "SCD1U16V2KX-3GP"
			(at 1.1811 -2.7051 180)
			(unlocked yes)
			(layer "F.Fab")
			(hide yes)
			(effects
				(font
					(size 1.016 1.016)
					(thickness 0.1524)
				)
			)
		)
		(property "Device Type" "C402H22"
			(at 1.1811 -4.2291 180)
			(unlocked yes)
			(layer "F.Fab")
			(hide yes)
			(effects
				(font
					(size 1.016 1.016)
					(thickness 0.1524)
				)
			)
		)
		(duplicate_pad_numbers_are_jumpers no)
		(fp_rect
			(start -0.4318 0.9525)
			(end 0.4318 -0.9525)
			(stroke
				(width 0)
				(type default)
			)
			(fill no)
			(layer "F.CrtYd")
		)
		(fp_rect
			(start -0.4318 0.9525)
			(end 0.4318 -0.9525)
			(stroke
				(width 0)
				(type default)
			)
			(fill no)
			(layer "F.Fab")
		)
		(pad "1" smd custom
			(at 0 -0.4445 180)
			(size 0.1524 0.1524)
			(layers "F.Cu" "F.Mask" "F.Paste")
			(net "VDD_IO_4")
			(options
				(clearance outline)
				(anchor circle)
			)
			(primitives
				(gr_poly
					(pts
						(arc
							(start 0.3048 -0.2032)
							(mid 0.275042 -0.275042)
							(end 0.2032 -0.3048)
						)
						(arc
							(start -0.2032 -0.3048)
							(mid -0.275042 -0.275042)
							(end -0.3048 -0.2032)
						)
						(arc
							(start -0.3048 0.2032)
							(mid -0.275042 0.275042)
							(end -0.2032 0.3048)
						)
						(arc
							(start 0.2032 0.3048)
							(mid 0.275042 0.275042)
							(end 0.3048 0.2032)
						)
					)
					(width 0)
					(fill yes)
				)
			)
		)
		(pad "2" smd custom
			(at 0 0.4445 180)
			(size 0.1524 0.1524)
			(layers "F.Cu" "F.Mask" "F.Paste")
			(net "GND")
			(options
				(clearance outline)
				(anchor circle)
			)
			(primitives
				(gr_poly
					(pts
						(arc
							(start 0.3048 -0.2032)
							(mid 0.275042 -0.275042)
							(end 0.2032 -0.3048)
						)
						(arc
							(start -0.2032 -0.3048)
							(mid -0.275042 -0.275042)
							(end -0.3048 -0.2032)
						)
						(arc
							(start -0.3048 0.2032)
							(mid -0.275042 0.275042)
							(end -0.2032 0.3048)
						)
						(arc
							(start 0.2032 0.3048)
							(mid 0.275042 0.275042)
							(end 0.3048 0.2032)
						)
					)
					(width 0)
					(fill yes)
				)
			)
		)
	)
	(footprint ""
		(layer "F.Cu")
		(at 33.1089 -411.6959)
		(property "Reference" "R9846"
			(at 0 0 0)
			(layer "F.SilkS")
			(hide yes)
			(effects
				(font
					(size 1.27 1.27)
				)
			)
		)
		(property "Value" "47KR2J-2-GP"
			(at 0.064008 -3.993896 0)
			(unlocked yes)
			(layer "F.Fab")
			(hide yes)
			(effects
				(font
					(size 1.016 1.016)
					(thickness 0.1524)
				)
			)
		)
		(property "Device Type" "R402H16"
			(at 0.064008 -5.517896 0)
			(unlocked yes)
			(layer "F.Fab")
			(hide yes)
			(effects
				(font
					(size 1.016 1.016)
					(thickness 0.1524)
				)
			)
		)
		(duplicate_pad_numbers_are_jumpers no)
		(fp_line
			(start -0.508 -0.9398)
			(end -0.508 0.9398)
			(stroke
				(width 0.1524)
				(type default)
			)
			(layer "F.SilkS")
		)
		(fp_line
			(start 0.508 -0.9398)
			(end -0.508 -0.9398)
			(stroke
				(width 0.1524)
				(type default)
			)
			(layer "F.SilkS")
		)
		(fp_rect
			(start -0.508 0.9398)
			(end 0.508 -0.9398)
			(stroke
				(width 0)
				(type default)
			)
			(fill no)
			(layer "F.CrtYd")
		)
		(fp_rect
			(start -0.508 0.9398)
			(end 0.508 -0.9398)
			(stroke
				(width 0)
				(type default)
			)
			(fill no)
			(layer "F.Fab")
		)
		(pad "1" smd custom
			(at 0 -0.4445)
			(size 0.1397 0.1397)
			(layers "F.Cu" "F.Mask" "F.Paste")
			(net "P12V")
			(options
				(clearance outline)
				(anchor circle)
			)
			(primitives
				(gr_poly
					(pts
						(arc
							(start -0.1778 -0.2794)
							(mid -0.249642 -0.249642)
							(end -0.2794 -0.1778)
						)
						(arc
							(start -0.2794 0.1778)
							(mid -0.249642 0.249642)
							(end -0.1778 0.2794)
						)
						(arc
							(start 0.1778 0.2794)
							(mid 0.249642 0.249642)
							(end 0.2794 0.1778)
						)
						(arc
							(start 0.2794 -0.1778)
							(mid 0.249642 -0.249642)
							(end 0.1778 -0.2794)
						)
					)
					(width 0)
					(fill yes)
				)
			)
		)
		(pad "2" smd custom
			(at 0 0.4445)
			(size 0.1397 0.1397)
			(layers "F.Cu" "F.Mask" "F.Paste")
			(net "P12V_MOST10_GATE")
			(options
				(clearance outline)
				(anchor circle)
			)
			(primitives
				(gr_poly
					(pts
						(arc
							(start -0.1778 -0.2794)
							(mid -0.249642 -0.249642)
							(end -0.2794 -0.1778)
						)
						(arc
							(start -0.2794 0.1778)
							(mid -0.249642 0.249642)
							(end -0.1778 0.2794)
						)
						(arc
							(start 0.1778 0.2794)
							(mid 0.249642 0.249642)
							(end 0.2794 0.1778)
						)
						(arc
							(start 0.2794 -0.1778)
							(mid 0.249642 -0.249642)
							(end 0.1778 -0.2794)
						)
					)
					(width 0)
					(fill yes)
				)
			)
		)
	)
	(footprint ""
		(layer "F.Cu")
		(at 13.937488 -425.843192 180)
		(property "Reference" "C9539"
			(at 0 0 180)
			(layer "F.SilkS")
			(hide yes)
			(effects
				(font
					(size 1.27 1.27)
				)
			)
		)
		(property "Value" "SCD01U50V2KX-1GP"
			(at 1.1811 -2.7051 180)
			(unlocked yes)
			(layer "F.Fab")
			(hide yes)
			(effects
				(font
					(size 1.016 1.016)
					(thickness 0.1524)
				)
			)
		)
		(property "Device Type" "C402H22"
			(at 1.1811 -4.2291 180)
			(unlocked yes)
			(layer "F.Fab")
			(hide yes)
			(effects
				(font
					(size 1.016 1.016)
					(thickness 0.1524)
				)
			)
		)
		(duplicate_pad_numbers_are_jumpers no)
		(fp_rect
			(start -0.4318 0.9525)
			(end 0.4318 -0.9525)
			(stroke
				(width 0)
				(type default)
			)
			(fill no)
			(layer "F.CrtYd")
		)
		(fp_rect
			(start -0.4318 0.9525)
			(end 0.4318 -0.9525)
			(stroke
				(width 0)
				(type default)
			)
			(fill no)
			(layer "F.Fab")
		)
		(pad "1" smd custom
			(at 0 -0.4445 180)
			(size 0.1524 0.1524)
			(layers "F.Cu" "F.Mask" "F.Paste")
			(net "PE_100M_CLK3_N")
			(options
				(clearance outline)
				(anchor circle)
			)
			(primitives
				(gr_poly
					(pts
						(arc
							(start 0.3048 -0.2032)
							(mid 0.275042 -0.275042)
							(end 0.2032 -0.3048)
						)
						(arc
							(start -0.2032 -0.3048)
							(mid -0.275042 -0.275042)
							(end -0.3048 -0.2032)
						)
						(arc
							(start -0.3048 0.2032)
							(mid -0.275042 0.275042)
							(end -0.2032 0.3048)
						)
						(arc
							(start 0.2032 0.3048)
							(mid 0.275042 0.275042)
							(end 0.3048 0.2032)
						)
					)
					(width 0)
					(fill yes)
				)
			)
		)
		(pad "2" smd custom
			(at 0 0.4445 180)
			(size 0.1524 0.1524)
			(layers "F.Cu" "F.Mask" "F.Paste")
			(net "PE_100M_CLK3_C_N")
			(options
				(clearance outline)
				(anchor circle)
			)
			(primitives
				(gr_poly
					(pts
						(arc
							(start 0.3048 -0.2032)
							(mid 0.275042 -0.275042)
							(end 0.2032 -0.3048)
						)
						(arc
							(start -0.2032 -0.3048)
							(mid -0.275042 -0.275042)
							(end -0.3048 -0.2032)
						)
						(arc
							(start -0.3048 0.2032)
							(mid -0.275042 0.275042)
							(end -0.2032 0.3048)
						)
						(arc
							(start 0.2032 0.3048)
							(mid 0.275042 0.275042)
							(end 0.3048 0.2032)
						)
					)
					(width 0)
					(fill yes)
				)
			)
		)
	)
)
